# T6G (Grand Teton) — schematic netlist excerpt (pin names and nets, part order shuffled) for the footprints in the layout excerpt that follows; sources: Cadence DE-HDL packaged netlist, KiCad conversion of 04192023_DAF0TMB3IC0_F0TG_MB_C_brd_V02_OCP.brd

C1107  Q_CAP  0.1UF 25V 10% X7R  pkg 0402  page 357 : A = P12V_E1S_0 ; B = GND
R1104  Q_RES  10K 1% CHIP  pkg 0201LF  page 309 : A = RST_RT_CPU0_P3_RESET_R_N ; B = GND
R1741  Q_RES  22 1% CHIP  pkg 0402LF  page 171 : A = JTAG_SCM_PLD_R_TMS ; B = JTAG_SCM_PLD_TMS

(kicad_pcb
	(version 20260206)
	(generator "pcbnew")
	(generator_version "10.0")
	(general
		(thickness 1.6)
		(legacy_teardrops no)
	)
	(paper "A4")
	(title_block
		(title "04192023_DAF0TMB3IC0_F0TG_MB_C_brd_V02_OCP.brd")
		(comment 1 "Grand Teton / footprints 2546-2548 of 8354")
	)
	(layers
		(0 "F.Cu" signal "TOP")
		(4 "In1.Cu" signal "GND")
		(6 "In2.Cu" signal "IN1")
		(8 "In3.Cu" signal "GND1")
		(10 "In4.Cu" signal "IN2")
		(12 "In5.Cu" signal "GND2")
		(14 "In6.Cu" signal "IN3")
		(16 "In7.Cu" signal "GND3")
		(18 "In8.Cu" signal "VCC")
		(20 "In9.Cu" signal "VCC1")
		(22 "In10.Cu" signal "GND4")
		(24 "In11.Cu" signal "IN4")
		(26 "In12.Cu" signal "GND5")
		(28 "In13.Cu" signal "IN5")
		(30 "In14.Cu" signal "GND6")
		(32 "In15.Cu" signal "IN6")
		(34 "In16.Cu" signal "GND7")
		(2 "B.Cu" signal "BOTTOM")
		(9 "F.Adhes" user "F.Adhesive")
		(11 "B.Adhes" user "B.Adhesive")
		(13 "F.Paste" user "Package Geometry/Pastemask Top")
		(15 "B.Paste" user "Package Geometry/Pastemask Bottom")
		(5 "F.SilkS" user "Ref Des/Silkscreen Top")
		(7 "B.SilkS" user "Ref Des/Silkscreen Bottom")
		(1 "F.Mask" user "Board Geometry/Soldermask Top")
		(3 "B.Mask" user "Board Geometry/Soldermask Bottom")
		(17 "Dwgs.User" user "User.Drawings")
		(19 "Cmts.User" user "User.Comments")
		(21 "Eco1.User" user "User.Eco1")
		(23 "Eco2.User" user "User.Eco2")
		(25 "Edge.Cuts" user "Board Geometry/Outline")
		(27 "Margin" user)
		(31 "F.CrtYd" user "Package Geometry/Place Bound Top")
		(29 "B.CrtYd" user "Package Geometry/Place Bound Bottom")
		(35 "F.Fab" user "Ref Des/Assembly Top")
		(33 "B.Fab" user "Ref Des/Assembly Bottom")
	)
	(footprint ""
		(layer "F.Cu")
		(at 105.64876 -61.087254 180)
		(property "Reference" "R1741"
			(at 0 0 180)
			(layer "F.SilkS")
			(hide yes)
			(effects
				(font
					(size 1.27 1.27)
				)
			)
		)
		(property "Value" ""
			(at 0 0 180)
			(layer "F.Fab")
			(effects
				(font
					(size 1.27 1.27)
				)
			)
		)
		(duplicate_pad_numbers_are_jumpers no)
		(fp_line
			(start 0.7874 0.4064)
			(end -0.7874 0.4064)
			(stroke
				(width 0.1524)
				(type default)
			)
			(layer "F.SilkS")
		)
		(fp_line
			(start 0.7874 -0.4064)
			(end 0.7874 0.4064)
			(stroke
				(width 0.1524)
				(type default)
			)
			(layer "F.SilkS")
		)
		(fp_line
			(start -0.7874 0.4064)
			(end -0.7874 -0.4064)
			(stroke
				(width 0.1524)
				(type default)
			)
			(layer "F.SilkS")
		)
		(fp_line
			(start -0.7874 -0.4064)
			(end 0.7874 -0.4064)
			(stroke
				(width 0.1524)
				(type default)
			)
			(layer "F.SilkS")
		)
		(fp_line
			(start 0.67945 0.3048)
			(end 0.120396 0.3048)
			(stroke
				(width 0.1)
				(type default)
			)
			(layer "F.Fab")
		)
		(fp_line
			(start 0.67945 -0.3048)
			(end 0.67945 0.3048)
			(stroke
				(width 0.1)
				(type default)
			)
			(layer "F.Fab")
		)
		(fp_line
			(start 0.12065 -0.2794)
			(end 0.12065 -0.3048)
			(stroke
				(width 0.1)
				(type default)
			)
			(layer "F.Fab")
		)
		(fp_line
			(start 0.12065 -0.3048)
			(end 0.67945 -0.3048)
			(stroke
				(width 0.1)
				(type default)
			)
			(layer "F.Fab")
		)
		(fp_line
			(start 0.120396 0.3048)
			(end 0.120396 0.2794)
			(stroke
				(width 0.1)
				(type default)
			)
			(layer "F.Fab")
		)
		(fp_line
			(start 0.120396 0.2794)
			(end -0.12065 0.2794)
			(stroke
				(width 0.1)
				(type default)
			)
			(layer "F.Fab")
		)
		(fp_line
			(start -0.12065 0.3048)
			(end -0.67945 0.3048)
			(stroke
				(width 0.1)
				(type default)
			)
			(layer "F.Fab")
		)
		(fp_line
			(start -0.12065 0.2794)
			(end -0.12065 0.3048)
			(stroke
				(width 0.1)
				(type default)
			)
			(layer "F.Fab")
		)
		(fp_line
			(start -0.12065 -0.2794)
			(end 0.12065 -0.2794)
			(stroke
				(width 0.1)
				(type default)
			)
			(layer "F.Fab")
		)
		(fp_line
			(start -0.12065 -0.305054)
			(end -0.12065 -0.2794)
			(stroke
				(width 0.1)
				(type default)
			)
			(layer "F.Fab")
		)
		(fp_line
			(start -0.67945 0.3048)
			(end -0.67945 -0.305054)
			(stroke
				(width 0.1)
				(type default)
			)
			(layer "F.Fab")
		)
		(fp_line
			(start -0.67945 -0.305054)
			(end -0.12065 -0.305054)
			(stroke
				(width 0.1)
				(type default)
			)
			(layer "F.Fab")
		)
		(pad "1" smd circle
			(at -0.40005 0 180)
			(size 0 0)
			(layers "F.Cu" "F.Mask" "F.Paste")
			(net "JTAG_SCM_PLD_R_TMS")
		)
		(pad "2" smd circle
			(at 0.40005 0 180)
			(size 0 0)
			(layers "F.Cu" "F.Mask" "F.Paste")
			(net "JTAG_SCM_PLD_TMS")
		)
	)
	(footprint ""
		(layer "F.Cu")
		(at 328.092308 -103.66375)
		(property "Reference" "C1107"
			(at 0 0 0)
			(layer "F.SilkS")
			(hide yes)
			(effects
				(font
					(size 1.27 1.27)
				)
			)
		)
		(property "Value" ""
			(at 0 0 0)
			(layer "F.Fab")
			(effects
				(font
					(size 1.27 1.27)
				)
			)
		)
		(duplicate_pad_numbers_are_jumpers no)
		(fp_line
			(start -0.7874 -0.4064)
			(end 0.7874 -0.4064)
			(stroke
				(width 0.1524)
				(type default)
			)
			(layer "F.SilkS")
		)
		(fp_line
			(start -0.7874 0.4064)
			(end -0.7874 -0.4064)
			(stroke
				(width 0.1524)
				(type default)
			)
			(layer "F.SilkS")
		)
		(fp_line
			(start 0.7874 -0.4064)
			(end 0.7874 0.4064)
			(stroke
				(width 0.1524)
				(type default)
			)
			(layer "F.SilkS")
		)
		(fp_line
			(start 0.7874 0.4064)
			(end -0.7874 0.4064)
			(stroke
				(width 0.1524)
				(type default)
			)
			(layer "F.SilkS")
		)
		(fp_line
			(start -0.67945 -0.305054)
			(end -0.12065 -0.305054)
			(stroke
				(width 0.1)
				(type default)
			)
			(layer "F.Fab")
		)
		(fp_line
			(start -0.67945 0.3048)
			(end -0.67945 -0.305054)
			(stroke
				(width 0.1)
				(type default)
			)
			(layer "F.Fab")
		)
		(fp_line
			(start -0.12065 -0.305054)
			(end -0.12065 -0.2794)
			(stroke
				(width 0.1)
				(type default)
			)
			(layer "F.Fab")
		)
		(fp_line
			(start -0.12065 -0.2794)
			(end 0.12065 -0.2794)
			(stroke
				(width 0.1)
				(type default)
			)
			(layer "F.Fab")
		)
		(fp_line
			(start -0.12065 0.2794)
			(end -0.12065 0.3048)
			(stroke
				(width 0.1)
				(type default)
			)
			(layer "F.Fab")
		)
		(fp_line
			(start -0.12065 0.3048)
			(end -0.67945 0.3048)
			(stroke
				(width 0.1)
				(type default)
			)
			(layer "F.Fab")
		)
		(fp_line
			(start 0.120396 0.2794)
			(end -0.12065 0.2794)
			(stroke
				(width 0.1)
				(type default)
			)
			(layer "F.Fab")
		)
		(fp_line
			(start 0.120396 0.3048)
			(end 0.120396 0.2794)
			(stroke
				(width 0.1)
				(type default)
			)
			(layer "F.Fab")
		)
		(fp_line
			(start 0.12065 -0.3048)
			(end 0.67945 -0.3048)
			(stroke
				(width 0.1)
				(type default)
			)
			(layer "F.Fab")
		)
		(fp_line
			(start 0.12065 -0.2794)
			(end 0.12065 -0.3048)
			(stroke
				(width 0.1)
				(type default)
			)
			(layer "F.Fab")
		)
		(fp_line
			(start 0.67945 -0.3048)
			(end 0.67945 0.3048)
			(stroke
				(width 0.1)
				(type default)
			)
			(layer "F.Fab")
		)
		(fp_line
			(start 0.67945 0.3048)
			(end 0.120396 0.3048)
			(stroke
				(width 0.1)
				(type default)
			)
			(layer "F.Fab")
		)
		(pad "1" smd circle
			(at -0.40005 0)
			(size 0 0)
			(layers "F.Cu" "F.Mask" "F.Paste")
			(net "P12V_E1S_0")
		)
		(pad "2" smd circle
			(at 0.40005 0)
			(size 0 0)
			(layers "F.Cu" "F.Mask" "F.Paste")
			(net "GND")
		)
	)
	(footprint ""
		(layer "F.Cu")
		(at 367.787936 -402.548852 -90)
		(property "Reference" "R1104"
			(at 0 0 270)
			(layer "F.SilkS")
			(hide yes)
			(effects
				(font
					(size 1.27 1.27)
				)
			)
		)
		(property "Value" ""
			(at 0 0 270)
			(layer "F.Fab")
			(effects
				(font
					(size 1.27 1.27)
				)
			)
		)
		(duplicate_pad_numbers_are_jumpers no)
		(fp_line
			(start -0.32512 0.175006)
			(end -0.32512 -0.175006)
			(stroke
				(width 0.1)
				(type default)
			)
			(layer "F.Fab")
		)
		(fp_line
			(start 0.32512 0.175006)
			(end -0.32512 0.175006)
			(stroke
				(width 0.1)
				(type default)
			)
			(layer "F.Fab")
		)
		(fp_line
			(start -0.32512 -0.175006)
			(end 0.32512 -0.175006)
			(stroke
				(width 0.1)
				(type default)
			)
			(layer "F.Fab")
		)
		(fp_line
			(start 0.32512 -0.175006)
			(end 0.32512 0.175006)
			(stroke
				(width 0.1)
				(type default)
			)
			(layer "F.Fab")
		)
		(pad "1" smd rect
			(at -0.2667 0 270)
			(size 0.3048 0.381)
			(layers "F.Cu" "F.Mask" "F.Paste")
			(net "RST_RT_CPU0_P3_RESET_R_N")
		)
		(pad "2" smd rect
			(at 0.2667 0 90)
			(size 0.3048 0.381)
			(layers "F.Cu" "F.Mask" "F.Paste")
			(net "GND")
		)
	)
)
